FILE_TYPE = CONNECTIVITY;
{Allegro Design Entry HDL 17.2-2016 S081 (4005846) 1/11/2022}
"PAGE_NUMBER" = 46;
0"NC";
1"NC_FM_IBL_ADR_TRIGGER_CPU1_R";
2"NC_FM_IBL_ADR_COMPLETE_CPU1_R";
3"NC_FM_IBL_ADR_ACK_CPU1";
4"PWRGD_PLT_AUX_CPU1_LVT3";
5"TP_FM_SYS_RST_CPU1_N";
6"TP_FM_IBL_PWRBTN_CPU1_N";
7"TP_I2C_S3M_RTC_CPU1_SCL";
8"NC_SPI_CPU1_NCM_CLK";
9"TP_CPU1_SSC_SYNC";
10"TP_FM_IBL_SLPS4_CPU1_R_N";
11"NC_ESPI_IBL_CPU1_IO2";
12"TP_JTAG_CPU1_PLD_TDO_R";
13"TP_FM_IBL_SLPS3_CPU1_R_N";
14"TP_JTAG_CPU1_PLD_TDI";
15"TP_JTAG_CPU1_PLD_TMS";
16"NC_UART_IBL_CPU1_TXD";
17"NC_UART_IBL_CPU1_CTS";
18"TP_FM_IBL_SLPS5_CPU1_R_N";
19"FM_S3M_CPU1_CPLD_CRC_ERROR";
20"PD_JTAG_CPU1_PLD_TCK";
21"NC_UART_IBL_CPU1_RXD";
22"NC_UART_IBL_CPU1_RTS";
23"NC_SPI_S3M_CPU1_CS1_LVC1_R_N";
24"TP_FM_WAKE_CPU1_N";
25"NC_SPI_S3M_CPU1_IO1_LVC1_R";
26"NC_SPI_CPU1_NCM_IO1";
27"NC_SPI_CPU1_NCM_CS0_N";
28"NC_SPI_S3M_CPU1_IO0_LVC1_R";
29"NC_SPI_CPU1_NCM_IO0";
30"NC_SPI_S3M_CPU1_OE_LVC1_R_N";
31"NC_SPI_S3M_CPU1_CS0_LVC1_R_N";
32"NC_SPI_CPU1_NCM_OE_N";
33"TP_I3C_MNG3_BMC_SW_SDA";
34"NC_SPI_S3M_CPU1_CLK_LVC1_R";
35"NC_SPI_S3M_CPU1_IO3_LVC1_R";
36"NC_ESPI_IBL_CPU1_ALERT1_N";
37"NC_SPI_S3M_CPU1_IO2_LVC1_R";
38"TP_I3C_MNG3_BMC_SW_SCL";
39"NC_ESPI_IBL_CPU1_ALERT0_N";
40"NC_ESPI_IBL_CPU1_CS0_N";
41"NC_ESPI_IBL_CPU1_CLK";
42"NC_ESPI_IBL_CPU1_RESET_N";
43"NC_ESPI_IBL_CPU1_OE_N";
44"NC_ESPI_IBL_CPU1_CS1_N";
45"NC_ESPI_IBL_CPU1_IO1";
46"NC_ESPI_IBL_CPU1_IO0";
47"NC_ESPI_IBL_CPU1_IO3";
48"TP_SGPIO_S3M_CPU1_GSXRST_N";
49"PUD_PCH_BOOT_MODE_CPU1";
50"TP_SGPIO_S3M_CPU1_GSXCLK";
51"TP_SGPIO_S3M_CPU1_GSXDOUT";
52"TP_SGPIO_S3M_CPU1_GSXDIN";
53"TP_PWRGD_S0_PWROK_CPU1_LVC1";
54"TP_CPU1_IBL_GRST_WARN_CPU1_N";
55"TP_I2C_S3M_RTC_CPU1_SDA";
56"TP_I2C_S3M_RTC_CPU1_RST_N";
57"TP_SGPIO_S3M_CPU1_GSXDLOAD";
58"FM_S3M_CPU1_LVC1_GPIO_4";
59"FM_S3M_CPU1_LVC1_GPIO_3";
60"FM_S3M_CPU1_LVC1_GPIO_2";
61"FM_S3M_CPU1_LVC1_GPIO_1";
62"FM_S3M_CPU1_LVC1_GPIO_0";
63"SMB_S3M_CPU1_SCL";
64"SMB_S3M_CPU1_SDA";
65"PU_S3M_CPU1_CPLD_CONFD";
66"FM_S3M_CPU1_CPLD_CONFIG_N";
67"PU_S3M_CPU1_CPLD_STATUS";
%"SOCKET4677_AZIF0045P001C01CS"
"3","(-3400,9125)","0","pure_quanta","I5";
;
PART_NUMBER"DGA^7000023"
PART_TYPE"SMLF"
MATERIAL"IO"
VALUE"SOCKET4677_AZIF0045-P001C01CS"
$LOCATION"U1"
CDS_LIB"pure_quanta"
NEEDS_NO_SIZE"TRUE"
CDS_LMAN_SYM_OUTLINE"-1050,1500,1050,-1450"
CDS_LOCATION"U1"
$SEC"3"
CDS_SEC"3";
"TEST_3"
$PN"CH65"67;
"TEST_2"
$PN"CK65"66;
"TEST_1"
$PN"CJ64"65;
"SMB_DATA"
$PN"CD63"64;
"SMB_CLK"
$PN"CE64"63;
"PARTITION_ID0"
$PN"BA70"62;
"PARTITION_ID1"
$PN"AV71"61;
"TEST_7"
$PN"AV69"60;
"TEST_8"
$PN"AY69"59;
"RSVD25"
$PN"AW70"58;
"RSVD105"
$PN"CJ66"57;
"RSVD103"
$PN"CJ25"56;
"RSVD102"
$PN"CJ23"55;
"RSVD101"
$PN"CJ21"54;
"RSVD100"
$PN"CH71"53;
"RSVD98"
$PN"CH63"52;
"RSVD94"
$PN"CF65"51;
"RSVD93"
$PN"CF63"50;
"TEST_6"
$PN"CF61"49;
"RSVD86"
$PN"CD65"48;
"RSVD64"
$PN"BM63"47;
"RSVD61"
$PN"BK63"46;
"RSVD58"
$PN"BJ64"45;
"RSVD56"
$PN"BH65"44;
"RSVD55"
$PN"BH63"43;
"RSVD53"
$PN"BG64"42;
"RSVD52"
$PN"BG62"41;
"RSVD50"
$PN"BF65"40;
"RSVD48"
$PN"BE62"39;
"RSVD47"
$PN"BE25"38;
"RSVD42"
$PN"BD65"37;
"RSVD41"
$PN"BD63"36;
"RSVD40"
$PN"BD61"35;
"RSVD39"
$PN"BC64"34;
"RSVD38"
$PN"BC25"33;
"RSVD36"
$PN"BB67"32;
"RSVD35"
$PN"BB61"31;
"RSVD34"
$PN"BA68"30;
"RSVD33"
$PN"BA66"29;
"RSVD32"
$PN"BA62"28;
"RSVD30"
$PN"AY67"27;
"RSVD28"
$PN"AY61"26;
"RSVD24"
$PN"AW64"25;
"RSVD23"
$PN"AW19"24;
"RSVD20"
$PN"AV63"23;
"RSVD156"
$PN"CY71"22;
"RSVD155"
$PN"CY69"21;
"TEST_5"
$PN"CY22"20;
"CD_INIT_ERROR"
$PN"CY20"19;
"RSVD144"
$PN"CW21"18;
"RSVD143"
$PN"CV71"17;
"RSVD142"
$PN"CV69"16;
"RSVD140"
$PN"CV22"15;
"RSVD137"
$PN"CT24"1;
"RSVD136"
$PN"CT22"14;
"RSVD131"
$PN"CR21"13;
"RSVD128"
$PN"CP24"2;
"RSVD127"
$PN"CP22"12;
"RSVD12"
$PN"AU64"11;
"RSVD124"
$PN"CN23"3;
"RSVD123"
$PN"CN21"10;
"RSVD117"
$PN"CL66"9;
"RSVD11"
$PN"AU62"8;
"RSVD114"
$PN"CL23"7;
"RSVD110"
$PN"CK24"6;
"RSVD109"
$PN"CK22"5;
"PLT_AUX_PWRGOOD"
$PN"CV20"4;
END.
